(kicad_pcb
	(version 20260206)
	(generator "pcbnew")
	(generator_version "10.0")
	(general
		(thickness 1.6)
		(legacy_teardrops no)
	)
	(paper "A4")
	(title_block
		(title "panther-plus-userver — 13130-1b_20150205.brd")
		(comment 1 "Honey Badger (Wiwynn) / footprint 282 of 1509 (U13), pads 1174-1283 of 1283")
	)
	(layers
		(0 "F.Cu" signal "TOP")
		(4 "In1.Cu" signal "L2")
		(6 "In2.Cu" signal "L3")
		(8 "In3.Cu" signal "L4")
		(10 "In4.Cu" signal "L5")
		(12 "In5.Cu" signal "L6")
		(14 "In6.Cu" signal "L7")
		(16 "In7.Cu" signal "L8")
		(18 "In8.Cu" signal "L9")
		(20 "In9.Cu" signal "L10")
		(22 "In10.Cu" signal "L11")
		(2 "B.Cu" signal "BOTTOM")
		(9 "F.Adhes" user "F.Adhesive")
		(11 "B.Adhes" user "B.Adhesive")
		(13 "F.Paste" user "Package Geometry/Pastemask Top")
		(15 "B.Paste" user "Package Geometry/Pastemask Bottom")
		(5 "F.SilkS" user "Ref Des/Silkscreen Top")
		(7 "B.SilkS" user "Ref Des/Silkscreen Bottom")
		(1 "F.Mask" user "Board Geometry/Soldermask Top")
		(3 "B.Mask" user "Board Geometry/Soldermask Bottom")
		(17 "Dwgs.User" user "User.Drawings")
		(19 "Cmts.User" user "User.Comments")
		(21 "Eco1.User" user "User.Eco1")
		(23 "Eco2.User" user "User.Eco2")
		(25 "Edge.Cuts" user "Board Geometry/Outline")
		(27 "Margin" user)
		(31 "F.CrtYd" user "Package Geometry/Place Bound Top")
		(29 "B.CrtYd" user "Package Geometry/Place Bound Bottom")
		(35 "F.Fab" user "Ref Des/Assembly Top")
		(33 "B.Fab" user "Ref Des/Assembly Bottom")
	)
	(footprint ""
		(layer "F.Cu")
		(at 95.849948 -39.200074 180)
		(property "Reference" "U13"
			(at 0 0 180)
			(layer "F.SilkS")
			(hide yes)
			(effects
				(font
					(size 1.27 1.27)
				)
			)
		)
		(property "Value" "AVOTON-GP"
			(at -25.0317 -2.4892 180)
			(unlocked yes)
			(layer "F.Fab")
			(hide yes)
			(effects
				(font
					(size 1.016 1.016)
					(thickness 0.1524)
				)
			)
		)
		(property "Device Type" "BGA1283M3428-3H197"
			(at -25.0317 -4.0132 180)
			(unlocked yes)
			(layer "F.Fab")
			(hide yes)
			(effects
				(font
					(size 1.016 1.016)
					(thickness 0.1524)
				)
			)
		)
		(duplicate_pad_numbers_are_jumpers no)
		(pad "T37" smd circle
			(at 1.89992 -5.50164 180)
			(size 0.381 0.381)
			(layers "F.Cu" "F.Mask" "F.Paste")
			(net "P1V0_STBY")
		)
		(pad "T39" smd circle
			(at 2.79908 -5.50164 180)
			(size 0.381 0.381)
			(layers "F.Cu" "F.Mask" "F.Paste")
			(net "P1V0_STBY")
		)
		(pad "T41" smd circle
			(at 3.50266 -5.77342 180)
			(size 0.3048 0.3048)
			(layers "F.Cu" "F.Mask" "F.Paste")
			(net "GND")
		)
		(pad "T42" smd circle
			(at 4.2037 -5.77342 180)
			(size 0.3048 0.3048)
			(layers "F.Cu" "F.Mask" "F.Paste")
			(net "GND")
		)
		(pad "T44" smd circle
			(at 5.20192 -5.50164 180)
			(size 0.381 0.381)
			(layers "F.Cu" "F.Mask" "F.Paste")
			(net "P1V0")
		)
		(pad "T45" smd circle
			(at 5.90042 -5.50164 180)
			(size 0.3048 0.3048)
			(layers "F.Cu" "F.Mask" "F.Paste")
			(net "P1V0")
		)
		(pad "T47" smd circle
			(at 6.80212 -5.50164 180)
			(size 0.3048 0.3048)
			(layers "F.Cu" "F.Mask" "F.Paste")
			(net "GND")
		)
		(pad "T48" smd circle
			(at 7.47522 -5.77342 180)
			(size 0.3048 0.3048)
			(layers "F.Cu" "F.Mask" "F.Paste")
			(net "BD_REV_2")
		)
		(pad "T50" smd circle
			(at 8.17626 -5.77342 180)
			(size 0.3048 0.3048)
			(layers "F.Cu" "F.Mask" "F.Paste")
			(net "SPI_CLK_GBE")
		)
		(pad "T52" smd circle
			(at 9.15416 -5.7277 180)
			(size 0.3048 0.3048)
			(layers "F.Cu" "F.Mask" "F.Paste")
			(net "GND")
		)
		(pad "T53" smd circle
			(at 9.91616 -5.7277 180)
			(size 0.3048 0.3048)
			(layers "F.Cu" "F.Mask" "F.Paste")
			(net "BD_ID_2")
		)
		(pad "T55" smd circle
			(at 10.67816 -5.7277 180)
			(size 0.3048 0.3048)
			(layers "F.Cu" "F.Mask" "F.Paste")
			(net "GBE_SMBALRT#")
		)
		(pad "T56" smd circle
			(at 11.44016 -5.7277 180)
			(size 0.3048 0.3048)
			(layers "F.Cu" "F.Mask" "F.Paste")
			(net "GND")
		)
		(pad "T58" smd circle
			(at 12.20216 -5.7277 180)
			(size 0.3048 0.3048)
			(layers "F.Cu" "F.Mask" "F.Paste")
			(net "GBE_SDP0")
		)
		(pad "T59" smd circle
			(at 12.96416 -5.7277 180)
			(size 0.3048 0.3048)
			(layers "F.Cu" "F.Mask" "F.Paste")
			(net "GBE_SMBDATA")
		)
		(pad "T62" smd circle
			(at 14.01318 -5.81914 180)
			(size 0.3048 0.3048)
			(layers "F.Cu" "F.Mask" "F.Paste")
			(net "GND")
		)
		(pad "T64" smd circle
			(at 15.24762 -5.78866 180)
			(size 0.3048 0.3048)
			(layers "F.Cu" "F.Mask" "F.Paste")
			(net "SATA3_TX_DN0")
		)
		(pad "U2" smd circle
			(at -15.75308 -5.12064 180)
			(size 0.3048 0.3048)
			(layers "F.Cu" "F.Mask" "F.Paste")
			(net "M_B_DQ41")
		)
		(pad "U4" smd circle
			(at -14.7955 -5.0673 180)
			(size 0.3048 0.3048)
			(layers "F.Cu" "F.Mask" "F.Paste")
			(net "M_B_DQ40")
		)
		(pad "U8" smd circle
			(at -12.96416 -5.48894 180)
			(size 0.3048 0.3048)
			(layers "F.Cu" "F.Mask" "F.Paste")
			(net "M_B_DQ39")
		)
		(pad "U9" smd circle
			(at -12.20216 -5.48894 180)
			(size 0.3048 0.3048)
			(layers "F.Cu" "F.Mask" "F.Paste")
			(net "GND")
		)
		(pad "U11" smd circle
			(at -11.44016 -5.48894 180)
			(size 0.3048 0.3048)
			(layers "F.Cu" "F.Mask" "F.Paste")
			(net "M_B_DQS_DP4")
		)
		(pad "U12" smd circle
			(at -10.67816 -5.48894 180)
			(size 0.3048 0.3048)
			(layers "F.Cu" "F.Mask" "F.Paste")
			(net "M_B_DQS_DN4")
		)
		(pad "U14" smd circle
			(at -9.91616 -5.48894 180)
			(size 0.3048 0.3048)
			(layers "F.Cu" "F.Mask" "F.Paste")
			(net "GND")
		)
		(pad "U15" smd circle
			(at -9.15416 -5.48894 180)
			(size 0.3048 0.3048)
			(layers "F.Cu" "F.Mask" "F.Paste")
			(net "M_B_DQ37")
		)
		(pad "U62" smd circle
			(at 14.06398 -5.1181 180)
			(size 0.3048 0.3048)
			(layers "F.Cu" "F.Mask" "F.Paste")
			(net "GND")
		)
		(pad "U63" smd circle
			(at 14.75232 -5.28574 180)
			(size 0.3048 0.3048)
			(layers "F.Cu" "F.Mask" "F.Paste")
			(net "GND")
		)
		(pad "U65" smd circle
			(at 15.80642 -5.36702 180)
			(size 0.3048 0.3048)
			(layers "F.Cu" "F.Mask" "F.Paste")
			(net "GND")
		)
		(pad "V5" smd circle
			(at -14.06398 -4.90982 180)
			(size 0.3048 0.3048)
			(layers "F.Cu" "F.Mask" "F.Paste")
			(net "GND")
		)
		(pad "V20" smd circle
			(at -6.72592 -4.8006 180)
			(size 0.3048 0.3048)
			(layers "F.Cu" "F.Mask" "F.Paste")
			(net "P1V0")
		)
		(pad "V21" smd circle
			(at -5.99948 -4.8006 180)
			(size 0.381 0.381)
			(layers "F.Cu" "F.Mask" "F.Paste")
			(net "P1V0")
		)
		(pad "V23" smd circle
			(at -5.20192 -4.8006 180)
			(size 0.381 0.381)
			(layers "F.Cu" "F.Mask" "F.Paste")
			(net "P1V0")
		)
		(pad "V25" smd circle
			(at -4.39928 -4.8006 180)
			(size 0.381 0.381)
			(layers "F.Cu" "F.Mask" "F.Paste")
			(net "P1V0")
		)
		(pad "V26" smd circle
			(at -3.60172 -4.8006 180)
			(size 0.381 0.381)
			(layers "F.Cu" "F.Mask" "F.Paste")
			(net "P1V0")
		)
		(pad "V28" smd circle
			(at -2.79908 -4.8006 180)
			(size 0.381 0.381)
			(layers "F.Cu" "F.Mask" "F.Paste")
			(net "VCCACKDDR1")
		)
		(pad "V29" smd circle
			(at -2.00152 -4.8006 180)
			(size 0.381 0.381)
			(layers "F.Cu" "F.Mask" "F.Paste")
			(net "VCCCLKDDR1")
		)
		(pad "V31" smd circle
			(at -1.19888 -4.8006 180)
			(size 0.381 0.381)
			(layers "F.Cu" "F.Mask" "F.Paste")
			(net "P1V35")
		)
		(pad "V32" smd circle
			(at -0.40132 -4.8006 180)
			(size 0.381 0.381)
			(layers "F.Cu" "F.Mask" "F.Paste")
			(net "GND")
		)
		(pad "V34" smd circle
			(at 0.40132 -4.8006 180)
			(size 0.381 0.381)
			(layers "F.Cu" "F.Mask" "F.Paste")
			(net "P1V35")
		)
		(pad "V36" smd circle
			(at 1.19888 -4.8006 180)
			(size 0.381 0.381)
			(layers "F.Cu" "F.Mask" "F.Paste")
			(net "GND")
		)
		(pad "V38" smd circle
			(at 2.00152 -4.8006 180)
			(size 0.381 0.381)
			(layers "F.Cu" "F.Mask" "F.Paste")
			(net "P1V0_STBY")
		)
		(pad "V39" smd circle
			(at 2.79908 -4.8006 180)
			(size 0.381 0.381)
			(layers "F.Cu" "F.Mask" "F.Paste")
			(net "P1V0_STBY")
		)
		(pad "V41" smd circle
			(at 3.60172 -4.8006 180)
			(size 0.381 0.381)
			(layers "F.Cu" "F.Mask" "F.Paste")
			(net "P1V0_STBY")
		)
		(pad "V42" smd circle
			(at 4.39928 -4.8006 180)
			(size 0.381 0.381)
			(layers "F.Cu" "F.Mask" "F.Paste")
			(net "GND")
		)
		(pad "V44" smd circle
			(at 5.20192 -4.8006 180)
			(size 0.381 0.381)
			(layers "F.Cu" "F.Mask" "F.Paste")
			(net "GND")
		)
		(pad "V46" smd circle
			(at 5.99948 -4.8006 180)
			(size 0.381 0.381)
			(layers "F.Cu" "F.Mask" "F.Paste")
			(net "P1V0")
		)
		(pad "V63" smd circle
			(at 14.5415 -4.60756 180)
			(size 0.3048 0.3048)
			(layers "F.Cu" "F.Mask" "F.Paste")
			(net "GBE_WOL")
		)
		(pad "V64" smd circle
			(at 15.3035 -4.55676 180)
			(size 0.3048 0.3048)
			(layers "F.Cu" "F.Mask" "F.Paste")
			(net "PMU_SLP_S45#")
		)
		(pad "V66" smd oval
			(at 16.24838 -4.60756 180)
			(size 0.3429 0.254)
			(layers "F.Cu" "F.Mask" "F.Paste")
			(net "SPI_CPU_WP#")
		)
		(pad "W1" smd oval
			(at -16.24838 -4.39928 180)
			(size 0.3429 0.254)
			(layers "F.Cu" "F.Mask" "F.Paste")
			(net "M_B_DQS_DP5")
		)
		(pad "W3" smd circle
			(at -15.3035 -4.45008 180)
			(size 0.3048 0.3048)
			(layers "F.Cu" "F.Mask" "F.Paste")
			(net "M_B_DQS_DN5")
		)
		(pad "W4" smd circle
			(at -14.5415 -4.39928 180)
			(size 0.3048 0.3048)
			(layers "F.Cu" "F.Mask" "F.Paste")
			(net "GND")
		)
		(pad "W7" smd circle
			(at -13.34516 -4.2037 180)
			(size 0.3048 0.3048)
			(layers "F.Cu" "F.Mask" "F.Paste")
			(net "M_B_DQS_DN6")
		)
		(pad "W8" smd circle
			(at -12.58316 -4.2037 180)
			(size 0.3048 0.3048)
			(layers "F.Cu" "F.Mask" "F.Paste")
			(net "M_B_DQ54")
		)
		(pad "W10" smd circle
			(at -11.82116 -4.2037 180)
			(size 0.3048 0.3048)
			(layers "F.Cu" "F.Mask" "F.Paste")
			(net "M_B_DQ50")
		)
		(pad "W11" smd circle
			(at -11.05916 -4.2037 180)
			(size 0.3048 0.3048)
			(layers "F.Cu" "F.Mask" "F.Paste")
			(net "GND")
		)
		(pad "W13" smd circle
			(at -10.29716 -4.2037 180)
			(size 0.3048 0.3048)
			(layers "F.Cu" "F.Mask" "F.Paste")
			(net "M_B_DQ49")
		)
		(pad "W14" smd circle
			(at -9.53516 -4.2037 180)
			(size 0.3048 0.3048)
			(layers "F.Cu" "F.Mask" "F.Paste")
			(net "M_B_DQ48")
		)
		(pad "W16" smd circle
			(at -8.77316 -4.2037 180)
			(size 0.3048 0.3048)
			(layers "F.Cu" "F.Mask" "F.Paste")
			(net "GND")
		)
		(pad "W17" smd circle
			(at -8.01116 -4.2037 180)
			(size 0.3048 0.3048)
			(layers "F.Cu" "F.Mask" "F.Paste")
			(net "GND")
		)
		(pad "W19" smd circle
			(at -7.24916 -4.2037 180)
			(size 0.3048 0.3048)
			(layers "F.Cu" "F.Mask" "F.Paste")
			(net "GND")
		)
		(pad "W21" smd circle
			(at -5.99948 -4.0005 180)
			(size 0.381 0.381)
			(layers "F.Cu" "F.Mask" "F.Paste")
			(net "P1V0")
		)
		(pad "W23" smd circle
			(at -5.20192 -4.0005 180)
			(size 0.381 0.381)
			(layers "F.Cu" "F.Mask" "F.Paste")
			(net "P1V0")
		)
		(pad "W25" smd circle
			(at -4.39928 -4.0005 180)
			(size 0.381 0.381)
			(layers "F.Cu" "F.Mask" "F.Paste")
			(net "P1V0")
		)
		(pad "W26" smd circle
			(at -3.60172 -4.0005 180)
			(size 0.381 0.381)
			(layers "F.Cu" "F.Mask" "F.Paste")
			(net "P1V0")
		)
		(pad "W28" smd circle
			(at -2.79908 -4.0005 180)
			(size 0.381 0.381)
			(layers "F.Cu" "F.Mask" "F.Paste")
			(net "VCCACKDDR1")
		)
		(pad "W29" smd circle
			(at -2.00152 -4.0005 180)
			(size 0.381 0.381)
			(layers "F.Cu" "F.Mask" "F.Paste")
			(net "VCCCLKDDR1")
		)
		(pad "W31" smd circle
			(at -1.19888 -4.0005 180)
			(size 0.381 0.381)
			(layers "F.Cu" "F.Mask" "F.Paste")
			(net "VCCA_PLLDDR1_AVN")
		)
		(pad "W32" smd circle
			(at -0.40132 -4.0005 180)
			(size 0.381 0.381)
			(layers "F.Cu" "F.Mask" "F.Paste")
			(net "GND")
		)
		(pad "W34" smd circle
			(at 0.40132 -4.0005 180)
			(size 0.381 0.381)
			(layers "F.Cu" "F.Mask" "F.Paste")
			(net "P1V35")
		)
		(pad "W36" smd circle
			(at 1.19888 -4.0005 180)
			(size 0.381 0.381)
			(layers "F.Cu" "F.Mask" "F.Paste")
			(net "GND")
		)
		(pad "W38" smd circle
			(at 2.00152 -4.0005 180)
			(size 0.381 0.381)
			(layers "F.Cu" "F.Mask" "F.Paste")
			(net "P1V0_STBY")
		)
		(pad "W39" smd circle
			(at 2.79908 -4.0005 180)
			(size 0.381 0.381)
			(layers "F.Cu" "F.Mask" "F.Paste")
			(net "GND")
		)
		(pad "W41" smd circle
			(at 3.60172 -4.0005 180)
			(size 0.381 0.381)
			(layers "F.Cu" "F.Mask" "F.Paste")
			(net "P1V0_STBY")
		)
		(pad "W42" smd circle
			(at 4.39928 -4.0005 180)
			(size 0.381 0.381)
			(layers "F.Cu" "F.Mask" "F.Paste")
			(net "GND")
		)
		(pad "W44" smd circle
			(at 5.20192 -4.0005 180)
			(size 0.381 0.381)
			(layers "F.Cu" "F.Mask" "F.Paste")
			(net "P1V0")
		)
		(pad "W46" smd circle
			(at 5.99948 -4.0005 180)
			(size 0.381 0.381)
			(layers "F.Cu" "F.Mask" "F.Paste")
			(net "P1V0")
		)
		(pad "W48" smd circle
			(at 7.24916 -4.44246 180)
			(size 0.3048 0.3048)
			(layers "F.Cu" "F.Mask" "F.Paste")
			(net "GND")
		)
		(pad "W50" smd circle
			(at 8.01116 -4.44246 180)
			(size 0.3048 0.3048)
			(layers "F.Cu" "F.Mask" "F.Paste")
			(net "BD_REV_1")
		)
		(pad "W51" smd circle
			(at 8.77316 -4.44246 180)
			(size 0.3048 0.3048)
			(layers "F.Cu" "F.Mask" "F.Paste")
			(net "SPI_MOSI_GBE")
		)
		(pad "W53" smd circle
			(at 9.53516 -4.44246 180)
			(size 0.3048 0.3048)
			(layers "F.Cu" "F.Mask" "F.Paste")
			(net "GND")
		)
		(pad "W54" smd circle
			(at 10.29716 -4.44246 180)
			(size 0.3048 0.3048)
			(layers "F.Cu" "F.Mask" "F.Paste")
			(net "FPGA_READY#")
		)
		(pad "W56" smd circle
			(at 11.05916 -4.44246 180)
			(size 0.3048 0.3048)
			(layers "F.Cu" "F.Mask" "F.Paste")
			(net "GBE_MDIO_CLK0")
		)
		(pad "W57" smd circle
			(at 11.82116 -4.44246 180)
			(size 0.3048 0.3048)
			(layers "F.Cu" "F.Mask" "F.Paste")
			(net "GND")
		)
		(pad "W59" smd circle
			(at 12.58316 -4.44246 180)
			(size 0.3048 0.3048)
			(layers "F.Cu" "F.Mask" "F.Paste")
			(net "GBE_MDIO_DATA0")
		)
		(pad "W60" smd circle
			(at 13.34516 -4.44246 180)
			(size 0.3048 0.3048)
			(layers "F.Cu" "F.Mask" "F.Paste")
			(net "SPI_MISO_R_GBE")
		)
		(pad "W62" smd circle
			(at 14.06398 -4.09448 180)
			(size 0.3048 0.3048)
			(layers "F.Cu" "F.Mask" "F.Paste")
			(net "GND")
		)
		(pad "Y2" smd circle
			(at -15.80642 -3.63982 180)
			(size 0.3048 0.3048)
			(layers "F.Cu" "F.Mask" "F.Paste")
			(net "M_B_DQ47")
		)
		(pad "Y4" smd circle
			(at -14.75232 -3.71856 180)
			(size 0.3048 0.3048)
			(layers "F.Cu" "F.Mask" "F.Paste")
			(net "M_B_DQ46")
		)
		(pad "Y5" smd circle
			(at -14.06398 -3.88874 180)
			(size 0.3048 0.3048)
			(layers "F.Cu" "F.Mask" "F.Paste")
			(net "GND")
		)
		(pad "Y7" smd circle
			(at -13.34516 -3.50266 180)
			(size 0.3048 0.3048)
			(layers "F.Cu" "F.Mask" "F.Paste")
			(net "M_B_DQS_DP6")
		)
		(pad "Y8" smd circle
			(at -12.58316 -3.50266 180)
			(size 0.3048 0.3048)
			(layers "F.Cu" "F.Mask" "F.Paste")
			(net "GND")
		)
		(pad "Y10" smd circle
			(at -11.82116 -3.50266 180)
			(size 0.3048 0.3048)
			(layers "F.Cu" "F.Mask" "F.Paste")
			(net "M_B_DQ55")
		)
		(pad "Y11" smd circle
			(at -11.05916 -3.50266 180)
			(size 0.3048 0.3048)
			(layers "F.Cu" "F.Mask" "F.Paste")
			(net "M_B_DQ51")
		)
		(pad "Y13" smd circle
			(at -10.29716 -3.50266 180)
			(size 0.3048 0.3048)
			(layers "F.Cu" "F.Mask" "F.Paste")
			(net "GND")
		)
		(pad "Y14" smd circle
			(at -9.53516 -3.50266 180)
			(size 0.3048 0.3048)
			(layers "F.Cu" "F.Mask" "F.Paste")
			(net "M_B_DQ53")
		)
		(pad "Y16" smd circle
			(at -8.77316 -3.50266 180)
			(size 0.3048 0.3048)
			(layers "F.Cu" "F.Mask" "F.Paste")
			(net "M_B_DQ52")
		)
		(pad "Y17" smd circle
			(at -8.01116 -3.50266 180)
			(size 0.3048 0.3048)
			(layers "F.Cu" "F.Mask" "F.Paste")
			(net "GND")
		)
		(pad "Y19" smd circle
			(at -7.24916 -3.50266 180)
			(size 0.3048 0.3048)
			(layers "F.Cu" "F.Mask" "F.Paste")
			(net "GND")
		)
		(pad "Y48" smd circle
			(at 7.24916 -3.74142 180)
			(size 0.3048 0.3048)
			(layers "F.Cu" "F.Mask" "F.Paste")
			(net "GND")
		)
		(pad "Y50" smd circle
			(at 8.01116 -3.74142 180)
			(size 0.3048 0.3048)
			(layers "F.Cu" "F.Mask" "F.Paste")
			(net "PMU_SLP_LAN#")
		)
		(pad "Y51" smd circle
			(at 8.77316 -3.74142 180)
			(size 0.3048 0.3048)
			(layers "F.Cu" "F.Mask" "F.Paste")
			(net "GND")
		)
		(pad "Y53" smd circle
			(at 9.53516 -3.74142 180)
			(size 0.3048 0.3048)
			(layers "F.Cu" "F.Mask" "F.Paste")
			(net "REV_CPU_FPGA_IO1")
		)
		(pad "Y54" smd circle
			(at 10.29716 -3.74142 180)
			(size 0.3048 0.3048)
			(layers "F.Cu" "F.Mask" "F.Paste")
			(net "REV_CPU_FPGA_IO0")
		)
		(pad "Y56" smd circle
			(at 11.05916 -3.74142 180)
			(size 0.3048 0.3048)
			(layers "F.Cu" "F.Mask" "F.Paste")
			(net "GND")
		)
		(pad "Y57" smd circle
			(at 11.82116 -3.74142 180)
			(size 0.3048 0.3048)
			(layers "F.Cu" "F.Mask" "F.Paste")
			(net "SUSPWRDNACK")
		)
		(pad "Y59" smd circle
			(at 12.58316 -3.74142 180)
			(size 0.3048 0.3048)
			(layers "F.Cu" "F.Mask" "F.Paste")
			(net "TP_CPU_RSVD13")
		)
		(pad "Y60" smd circle
			(at 13.34516 -3.74142 180)
			(size 0.3048 0.3048)
			(layers "F.Cu" "F.Mask" "F.Paste")
			(net "GND")
		)
		(pad "Y63" smd circle
			(at 14.7955 -3.937 180)
			(size 0.3048 0.3048)
			(layers "F.Cu" "F.Mask" "F.Paste")
			(net "XDP_CPU_RESET#")
		)
		(pad "Y65" smd circle
			(at 15.75308 -3.8862 180)
			(size 0.3048 0.3048)
			(layers "F.Cu" "F.Mask" "F.Paste")
			(net "SPI_CPU_CS0#")
		)
	)
)
